(kicad_pcb
	(version 20260206)
	(generator "pcbnew")
	(generator_version "10.0")
	(general
		(thickness 1.6)
		(legacy_teardrops no)
	)
	(paper "A4")
	(title_block
		(title "03242023_DA0F0TMBIJ0_F0T_Motherboard_J_brd_V01_OCP.brd")
		(comment 1 "Grand Teton / footprint 4091 of 6105 (U38), pads 1-81 of 81")
	)
	(layers
		(0 "F.Cu" signal "TOP")
		(4 "In1.Cu" signal "GND")
		(6 "In2.Cu" signal "IN1")
		(8 "In3.Cu" signal "GND1")
		(10 "In4.Cu" signal "IN2")
		(12 "In5.Cu" signal "GND2")
		(14 "In6.Cu" signal "IN3")
		(16 "In7.Cu" signal "GND3")
		(18 "In8.Cu" signal "VCC")
		(20 "In9.Cu" signal "VCC1")
		(22 "In10.Cu" signal "GND4")
		(24 "In11.Cu" signal "IN4")
		(26 "In12.Cu" signal "GND5")
		(28 "In13.Cu" signal "IN5")
		(30 "In14.Cu" signal "GND6")
		(32 "In15.Cu" signal "IN6")
		(34 "In16.Cu" signal "GND7")
		(2 "B.Cu" signal "BOTTOM")
		(9 "F.Adhes" user "F.Adhesive")
		(11 "B.Adhes" user "B.Adhesive")
		(13 "F.Paste" user "Package Geometry/Pastemask Top")
		(15 "B.Paste" user "Package Geometry/Pastemask Bottom")
		(5 "F.SilkS" user "Ref Des/Silkscreen Top")
		(7 "B.SilkS" user "Ref Des/Silkscreen Bottom")
		(1 "F.Mask" user "Board Geometry/Soldermask Top")
		(3 "B.Mask" user "Board Geometry/Soldermask Bottom")
		(17 "Dwgs.User" user "User.Drawings")
		(19 "Cmts.User" user "User.Comments")
		(21 "Eco1.User" user "User.Eco1")
		(23 "Eco2.User" user "User.Eco2")
		(25 "Edge.Cuts" user "Board Geometry/Outline")
		(27 "Margin" user)
		(31 "F.CrtYd" user "Package Geometry/Place Bound Top")
		(29 "B.CrtYd" user "Package Geometry/Place Bound Bottom")
		(35 "F.Fab" user "Ref Des/Assembly Top")
		(33 "B.Fab" user "Ref Des/Assembly Bottom")
	)
	(footprint ""
		(layer "F.Cu")
		(at 234.998006 -126.767844 180)
		(property "Reference" "U38"
			(at -6.147308 -6.293104 0)
			(unlocked yes)
			(layer "F.SilkS")
			(effects
				(font
					(size 0.7874 0.5842)
					(thickness 0.1524)
				)
				(justify left)
			)
		)
		(property "Value" ""
			(at 0 0 180)
			(layer "F.Fab")
			(effects
				(font
					(size 1.27 1.27)
				)
			)
		)
		(duplicate_pad_numbers_are_jumpers no)
		(pad "A1" smd circle
			(at -2.750058 -2.750058 180)
			(size 0.2286 0.2286)
			(layers "F.Cu" "F.Mask" "F.Paste")
			(net "CLK_100M_OCP_V3_2_D_R_DP")
		)
		(pad "A2" smd circle
			(at -2.249932 -2.750058 180)
			(size 0.2286 0.2286)
			(layers "F.Cu" "F.Mask" "F.Paste")
			(net "CLK_100M_OCP_V3_2_C_R_DN")
		)
		(pad "A3" smd circle
			(at -1.75006 -2.750058 180)
			(size 0.2286 0.2286)
			(layers "F.Cu" "F.Mask" "F.Paste")
			(net "CLK_100M_OCP_V3_2_C_R_DP")
		)
		(pad "A4" smd circle
			(at -1.249934 -2.750058 180)
			(size 0.2286 0.2286)
			(layers "F.Cu" "F.Mask" "F.Paste")
			(net "CLK_100M_OCP_V3_2_B_R_DN")
		)
		(pad "A5" smd circle
			(at -0.750062 -2.750058 180)
			(size 0.2286 0.2286)
			(layers "F.Cu" "F.Mask" "F.Paste")
			(net "CLK_100M_OCP_V3_2_B_R_DP")
		)
		(pad "A6" smd circle
			(at -0.249936 -2.750058 180)
			(size 0.2286 0.2286)
			(layers "F.Cu" "F.Mask" "F.Paste")
			(net "CLK_100M_OCP_V3_2_A_R_DN")
		)
		(pad "A7" smd circle
			(at 0.249936 -2.750058 180)
			(size 0.2286 0.2286)
			(layers "F.Cu" "F.Mask" "F.Paste")
			(net "CLK_100M_OCP_V3_2_A_R_DP")
		)
		(pad "A8" smd circle
			(at 0.750062 -2.750058 180)
			(size 0.2286 0.2286)
			(layers "F.Cu" "F.Mask" "F.Paste")
			(net "TP_CLK_100M_DIF13_DN")
		)
		(pad "A9" smd circle
			(at 1.249934 -2.750058 180)
			(size 0.2286 0.2286)
			(layers "F.Cu" "F.Mask" "F.Paste")
			(net "TP_CLK_100M_DIF13_DP")
		)
		(pad "A10" smd circle
			(at 1.75006 -2.750058 180)
			(size 0.2286 0.2286)
			(layers "F.Cu" "F.Mask" "F.Paste")
			(net "CLK_100M_OCP_SFF_3_R_DN")
		)
		(pad "A11" smd circle
			(at 2.249932 -2.750058 180)
			(size 0.2286 0.2286)
			(layers "F.Cu" "F.Mask" "F.Paste")
			(net "CLK_100M_OCP_SFF_3_R_DP")
		)
		(pad "A12" smd circle
			(at 2.750058 -2.750058 180)
			(size 0.2286 0.2286)
			(layers "F.Cu" "F.Mask" "F.Paste")
			(net "CLK_100M_OCP_SFF_2_R_DN")
		)
		(pad "B1" smd circle
			(at -2.750058 -2.249932 180)
			(size 0.2286 0.2286)
			(layers "F.Cu" "F.Mask" "F.Paste")
			(net "CLK_100M_OCP_V3_2_D_R_DN")
		)
		(pad "B2" smd circle
			(at -2.249932 -2.249932 180)
			(size 0.2286 0.2286)
			(layers "F.Cu" "F.Mask" "F.Paste")
			(net "P3V3_DB2000_VDD")
		)
		(pad "B3" smd circle
			(at -1.75006 -2.249932 180)
			(size 0.2286 0.2286)
			(layers "F.Cu" "F.Mask" "F.Paste")
			(net "NC_CLK_100M_DB2000_NC1")
		)
		(pad "B4" smd circle
			(at -1.249934 -2.249932 180)
			(size 0.2286 0.2286)
			(layers "F.Cu" "F.Mask" "F.Paste")
			(net "PD_DB2000_SMB_SA0")
		)
		(pad "B5" smd circle
			(at -0.750062 -2.249932 180)
			(size 0.2286 0.2286)
			(layers "F.Cu" "F.Mask" "F.Paste")
			(net "NC_CLK_100M_DB2000_NC2")
		)
		(pad "B6" smd circle
			(at -0.249936 -2.249932 180)
			(size 0.2286 0.2286)
			(layers "F.Cu" "F.Mask" "F.Paste")
			(net "P3V3_DB2000_VDDA")
		)
		(pad "B7" smd circle
			(at 0.249936 -2.249932 180)
			(size 0.2286 0.2286)
			(layers "F.Cu" "F.Mask" "F.Paste")
			(net "NC_CLK_100M_DB2000_NC3")
		)
		(pad "B8" smd circle
			(at 0.750062 -2.249932 180)
			(size 0.2286 0.2286)
			(layers "F.Cu" "F.Mask" "F.Paste")
			(net "PD_DB2000_SMB_SA1")
		)
		(pad "B9" smd circle
			(at 1.249934 -2.249932 180)
			(size 0.2286 0.2286)
			(layers "F.Cu" "F.Mask" "F.Paste")
			(net "NC_CLK_100M_DB2000_NC4")
		)
		(pad "B10" smd circle
			(at 1.75006 -2.249932 180)
			(size 0.2286 0.2286)
			(layers "F.Cu" "F.Mask" "F.Paste")
			(net "FM_DB2000_12_OE_N")
		)
		(pad "B11" smd circle
			(at 2.249932 -2.249932 180)
			(size 0.2286 0.2286)
			(layers "F.Cu" "F.Mask" "F.Paste")
			(net "P3V3_DB2000_VDD")
		)
		(pad "B12" smd circle
			(at 2.750058 -2.249932 180)
			(size 0.2286 0.2286)
			(layers "F.Cu" "F.Mask" "F.Paste")
			(net "CLK_100M_OCP_SFF_2_R_DP")
		)
		(pad "C1" smd circle
			(at -2.750058 -1.75006 180)
			(size 0.2286 0.2286)
			(layers "F.Cu" "F.Mask" "F.Paste")
			(net "TP_CLK_100M_DIF18_DP")
		)
		(pad "C2" smd circle
			(at -2.249932 -1.75006 180)
			(size 0.2286 0.2286)
			(layers "F.Cu" "F.Mask" "F.Paste")
			(net "NC_CLK_100M_DB2000_NC5")
		)
		(pad "C11" smd circle
			(at 2.249932 -1.75006 180)
			(size 0.2286 0.2286)
			(layers "F.Cu" "F.Mask" "F.Paste")
			(net "FM_DB2000_11_OE_N")
		)
		(pad "C12" smd circle
			(at 2.750058 -1.75006 180)
			(size 0.2286 0.2286)
			(layers "F.Cu" "F.Mask" "F.Paste")
			(net "CLK_100M_OCP_SFF_1_R_DN")
		)
		(pad "D1" smd circle
			(at -2.750058 -1.249934 180)
			(size 0.2286 0.2286)
			(layers "F.Cu" "F.Mask" "F.Paste")
			(net "TP_CLK_100M_DIF18_DN")
		)
		(pad "D2" smd circle
			(at -2.249932 -1.249934 180)
			(size 0.2286 0.2286)
			(layers "F.Cu" "F.Mask" "F.Paste")
			(net "NC_CLK_100M_DB2000_NC6")
		)
		(pad "D11" smd circle
			(at 2.249932 -1.249934 180)
			(size 0.2286 0.2286)
			(layers "F.Cu" "F.Mask" "F.Paste")
			(net "NC_CLK_100M_DB2000_NC7")
		)
		(pad "D12" smd circle
			(at 2.750058 -1.249934 180)
			(size 0.2286 0.2286)
			(layers "F.Cu" "F.Mask" "F.Paste")
			(net "CLK_100M_OCP_SFF_1_R_DP")
		)
		(pad "E1" smd circle
			(at -2.750058 -0.750062 180)
			(size 0.2286 0.2286)
			(layers "F.Cu" "F.Mask" "F.Paste")
			(net "TP_CLK_100M_DIF19_DP")
		)
		(pad "E2" smd circle
			(at -2.249932 -0.750062 180)
			(size 0.2286 0.2286)
			(layers "F.Cu" "F.Mask" "F.Paste")
			(net "FM_DB2000_VSBEN")
		)
		(pad "E11" smd circle
			(at 2.249932 -0.750062 180)
			(size 0.2286 0.2286)
			(layers "F.Cu" "F.Mask" "F.Paste")
			(net "FM_DB2000_10_OE_N")
		)
		(pad "E12" smd circle
			(at 2.750058 -0.750062 180)
			(size 0.2286 0.2286)
			(layers "F.Cu" "F.Mask" "F.Paste")
			(net "FM_DB2000_9_OE_N")
		)
		(pad "F1" smd circle
			(at -2.750058 -0.249936 180)
			(size 0.2286 0.2286)
			(layers "F.Cu" "F.Mask" "F.Paste")
			(net "TP_CLK_100M_DIF19_DN")
		)
		(pad "F2" smd circle
			(at -2.249932 -0.249936 180)
			(size 0.2286 0.2286)
			(layers "F.Cu" "F.Mask" "F.Paste")
			(net "NC_CLK_100M_DB2000_NC8")
		)
		(pad "F11" smd circle
			(at 2.249932 -0.249936 180)
			(size 0.2286 0.2286)
			(layers "F.Cu" "F.Mask" "F.Paste")
			(net "NC_CLK_100M_DB2000_NC9")
		)
		(pad "F12" smd circle
			(at 2.750058 -0.249936 180)
			(size 0.2286 0.2286)
			(layers "F.Cu" "F.Mask" "F.Paste")
			(net "CLK_100M_OCP_SFF_0_R_DN")
		)
		(pad "G1" smd circle
			(at -2.750058 0.249936 180)
			(size 0.2286 0.2286)
			(layers "F.Cu" "F.Mask" "F.Paste")
			(net "CLK_100M_DB2000_DP")
		)
		(pad "G2" smd circle
			(at -2.249932 0.249936 180)
			(size 0.2286 0.2286)
			(layers "F.Cu" "F.Mask" "F.Paste")
			(net "NC_CLK_100M_DB2000_NC10")
		)
		(pad "G11" smd circle
			(at 2.249932 0.249936 180)
			(size 0.2286 0.2286)
			(layers "F.Cu" "F.Mask" "F.Paste")
			(net "NC_CLK_100M_DB2000_NC11")
		)
		(pad "G12" smd circle
			(at 2.750058 0.249936 180)
			(size 0.2286 0.2286)
			(layers "F.Cu" "F.Mask" "F.Paste")
			(net "CLK_100M_OCP_SFF_0_R_DP")
		)
		(pad "H1" smd circle
			(at -2.750058 0.750062 180)
			(size 0.2286 0.2286)
			(layers "F.Cu" "F.Mask" "F.Paste")
			(net "CLK_100M_DB2000_DN")
		)
		(pad "H2" smd circle
			(at -2.249932 0.750062 180)
			(size 0.2286 0.2286)
			(layers "F.Cu" "F.Mask" "F.Paste")
			(net "P3V3_DB2000_VDDR")
		)
		(pad "H11" smd circle
			(at 2.249932 0.750062 180)
			(size 0.2286 0.2286)
			(layers "F.Cu" "F.Mask" "F.Paste")
			(net "FM_DB2000_8_OE_N")
		)
		(pad "H12" smd circle
			(at 2.750058 0.750062 180)
			(size 0.2286 0.2286)
			(layers "F.Cu" "F.Mask" "F.Paste")
			(net "CLK_100M_GPU_SWB_REF_DN")
		)
		(pad "J1" smd circle
			(at -2.750058 1.249934 180)
			(size 0.2286 0.2286)
			(layers "F.Cu" "F.Mask" "F.Paste")
			(net "CLK_100M_DB2000_CPU0_BCLK0_DP")
		)
		(pad "J2" smd circle
			(at -2.249932 1.249934 180)
			(size 0.2286 0.2286)
			(layers "F.Cu" "F.Mask" "F.Paste")
			(net "NC_CLK_100M_DB2000_NC12")
		)
		(pad "J11" smd circle
			(at 2.249932 1.249934 180)
			(size 0.2286 0.2286)
			(layers "F.Cu" "F.Mask" "F.Paste")
			(net "NC_CLK_100M_DB2000_NC13")
		)
		(pad "J12" smd circle
			(at 2.750058 1.249934 180)
			(size 0.2286 0.2286)
			(layers "F.Cu" "F.Mask" "F.Paste")
			(net "CLK_100M_GPU_SWB_REF_DP")
		)
		(pad "K1" smd circle
			(at -2.750058 1.75006 180)
			(size 0.2286 0.2286)
			(layers "F.Cu" "F.Mask" "F.Paste")
			(net "CLK_100M_DB2000_CPU0_BCLK0_DN")
		)
		(pad "K2" smd circle
			(at -2.249932 1.75006 180)
			(size 0.2286 0.2286)
			(layers "F.Cu" "F.Mask" "F.Paste")
			(net "NC_CLK_100M_DB2000_NC14")
		)
		(pad "K11" smd circle
			(at 2.249932 1.75006 180)
			(size 0.2286 0.2286)
			(layers "F.Cu" "F.Mask" "F.Paste")
			(net "FM_DB2000_1_OE_N")
		)
		(pad "K12" smd circle
			(at 2.750058 1.75006 180)
			(size 0.2286 0.2286)
			(layers "F.Cu" "F.Mask" "F.Paste")
			(net "CLK_100M_DB2000_CPU1_BCLK3_DN")
		)
		(pad "L1" smd circle
			(at -2.750058 2.249932 180)
			(size 0.2286 0.2286)
			(layers "F.Cu" "F.Mask" "F.Paste")
			(net "CLK_100M_DB2000_CPU0_BCLK1_DP")
		)
		(pad "L2" smd circle
			(at -2.249932 2.249932 180)
			(size 0.2286 0.2286)
			(layers "F.Cu" "F.Mask" "F.Paste")
			(net "P3V3_DB2000_VDD")
		)
		(pad "L3" smd circle
			(at -1.75006 2.249932 180)
			(size 0.2286 0.2286)
			(layers "F.Cu" "F.Mask" "F.Paste")
			(net "NC_CLK_100M_DB2000_NC17")
		)
		(pad "L4" smd circle
			(at -1.249934 2.249932 180)
			(size 0.2286 0.2286)
			(layers "F.Cu" "F.Mask" "F.Paste")
			(net "SMB_HOST_DB2000_3V3AUX_SDA")
		)
		(pad "L5" smd circle
			(at -0.750062 2.249932 180)
			(size 0.2286 0.2286)
			(layers "F.Cu" "F.Mask" "F.Paste")
			(net "SMB_HOST_DB2000_3V3AUX_SCL")
		)
		(pad "L6" smd circle
			(at -0.249936 2.249932 180)
			(size 0.2286 0.2286)
			(layers "F.Cu" "F.Mask" "F.Paste")
			(net "NC_CLK_100M_DB2000_NC15")
		)
		(pad "L7" smd circle
			(at 0.249936 2.249932 180)
			(size 0.2286 0.2286)
			(layers "F.Cu" "F.Mask" "F.Paste")
			(net "NC_CLK_100M_DB2000_NC16")
		)
		(pad "L8" smd circle
			(at 0.750062 2.249932 180)
			(size 0.2286 0.2286)
			(layers "F.Cu" "F.Mask" "F.Paste")
			(net "FM_DB2000_1_OE_N")
		)
		(pad "L9" smd circle
			(at 1.249934 2.249932 180)
			(size 0.2286 0.2286)
			(layers "F.Cu" "F.Mask" "F.Paste")
			(net "NC_CLK_100M_DB2000_NC18")
		)
		(pad "L10" smd circle
			(at 1.75006 2.249932 180)
			(size 0.2286 0.2286)
			(layers "F.Cu" "F.Mask" "F.Paste")
			(net "FM_DB2000_1_OE_N")
		)
		(pad "L11" smd circle
			(at 2.249932 2.249932 180)
			(size 0.2286 0.2286)
			(layers "F.Cu" "F.Mask" "F.Paste")
			(net "P3V3_DB2000_VDD")
		)
		(pad "L12" smd circle
			(at 2.750058 2.249932 180)
			(size 0.2286 0.2286)
			(layers "F.Cu" "F.Mask" "F.Paste")
			(net "CLK_100M_DB2000_CPU1_BCLK3_DP")
		)
		(pad "M1" smd circle
			(at -2.750058 2.750058 180)
			(size 0.2286 0.2286)
			(layers "F.Cu" "F.Mask" "F.Paste")
			(net "CLK_100M_DB2000_CPU0_BCLK1_DN")
		)
		(pad "M2" smd circle
			(at -2.249932 2.750058 180)
			(size 0.2286 0.2286)
			(layers "F.Cu" "F.Mask" "F.Paste")
			(net "CLK_100M_DB2000_CPU0_BCLK2_DP")
		)
		(pad "M3" smd circle
			(at -1.75006 2.750058 180)
			(size 0.2286 0.2286)
			(layers "F.Cu" "F.Mask" "F.Paste")
			(net "CLK_100M_DB2000_CPU0_BCLK2_DN")
		)
		(pad "M4" smd circle
			(at -1.249934 2.750058 180)
			(size 0.2286 0.2286)
			(layers "F.Cu" "F.Mask" "F.Paste")
			(net "CLK_100M_DB2000_CPU0_BCLK3_DP")
		)
		(pad "M5" smd circle
			(at -0.750062 2.750058 180)
			(size 0.2286 0.2286)
			(layers "F.Cu" "F.Mask" "F.Paste")
			(net "CLK_100M_DB2000_CPU0_BCLK3_DN")
		)
		(pad "M6" smd circle
			(at -0.249936 2.750058 180)
			(size 0.2286 0.2286)
			(layers "F.Cu" "F.Mask" "F.Paste")
			(net "FM_DB2000_DEV_EN")
		)
		(pad "M7" smd circle
			(at 0.249936 2.750058 180)
			(size 0.2286 0.2286)
			(layers "F.Cu" "F.Mask" "F.Paste")
			(net "CLK_100M_DB2000_CPU1_BCLK0_DP")
		)
		(pad "M8" smd circle
			(at 0.750062 2.750058 180)
			(size 0.2286 0.2286)
			(layers "F.Cu" "F.Mask" "F.Paste")
			(net "CLK_100M_DB2000_CPU1_BCLK0_DN")
		)
		(pad "M9" smd circle
			(at 1.249934 2.750058 180)
			(size 0.2286 0.2286)
			(layers "F.Cu" "F.Mask" "F.Paste")
			(net "CLK_100M_DB2000_CPU1_BCLK1_DP")
		)
		(pad "M10" smd circle
			(at 1.75006 2.750058 180)
			(size 0.2286 0.2286)
			(layers "F.Cu" "F.Mask" "F.Paste")
			(net "CLK_100M_DB2000_CPU1_BCLK1_DN")
		)
		(pad "M11" smd circle
			(at 2.249932 2.750058 180)
			(size 0.2286 0.2286)
			(layers "F.Cu" "F.Mask" "F.Paste")
			(net "CLK_100M_DB2000_CPU1_BCLK2_DP")
		)
		(pad "M12" smd circle
			(at 2.750058 2.750058 180)
			(size 0.2286 0.2286)
			(layers "F.Cu" "F.Mask" "F.Paste")
			(net "CLK_100M_DB2000_CPU1_BCLK2_DN")
		)
		(pad "TH" smd circle
			(at 0 0 180)
			(size 0 0)
			(layers "F.Cu" "F.Mask" "F.Paste")
			(net "GND")
		)
	)
)
